(kicad_pcb
	(version 20260206)
	(generator "pcbnew")
	(generator_version "10.0")
	(general
		(thickness 1.6)
		(legacy_teardrops no)
	)
	(paper "A4")
	(title_block
		(title "panther-plus-userver — 13130-1b_20150205.brd")
		(comment 1 "Honey Badger (Wiwynn) / footprint 1214 of 1509 (DIMM3), pads 184-190 of 210")
	)
	(layers
		(0 "F.Cu" signal "TOP")
		(4 "In1.Cu" signal "L2")
		(6 "In2.Cu" signal "L3")
		(8 "In3.Cu" signal "L4")
		(10 "In4.Cu" signal "L5")
		(12 "In5.Cu" signal "L6")
		(14 "In6.Cu" signal "L7")
		(16 "In7.Cu" signal "L8")
		(18 "In8.Cu" signal "L9")
		(20 "In9.Cu" signal "L10")
		(22 "In10.Cu" signal "L11")
		(2 "B.Cu" signal "BOTTOM")
		(9 "F.Adhes" user "F.Adhesive")
		(11 "B.Adhes" user "B.Adhesive")
		(13 "F.Paste" user "Package Geometry/Pastemask Top")
		(15 "B.Paste" user "Package Geometry/Pastemask Bottom")
		(5 "F.SilkS" user "Ref Des/Silkscreen Top")
		(7 "B.SilkS" user "Ref Des/Silkscreen Bottom")
		(1 "F.Mask" user "Board Geometry/Soldermask Top")
		(3 "B.Mask" user "Board Geometry/Soldermask Bottom")
		(17 "Dwgs.User" user "User.Drawings")
		(19 "Cmts.User" user "User.Comments")
		(21 "Eco1.User" user "User.Eco1")
		(23 "Eco2.User" user "User.Eco2")
		(25 "Edge.Cuts" user "Board Geometry/Outline")
		(27 "Margin" user)
		(31 "F.CrtYd" user "Package Geometry/Place Bound Top")
		(29 "B.CrtYd" user "Package Geometry/Place Bound Bottom")
		(35 "F.Fab" user "Ref Des/Assembly Top")
		(33 "B.Fab" user "Ref Des/Assembly Bottom")
	)
	(footprint ""
		(layer "B.Cu")
		(at 159.999934 -5.790692)
		(property "Reference" "DIMM3"
			(at 0 0 0)
			(layer "B.SilkS")
			(hide yes)
			(effects
				(font
					(size 1.27 1.27)
				)
				(justify mirror)
			)
		)
		(property "Value" "DDR3-204P-142-COLAY-1-GP-U"
			(at 41.312338 -16.676878 0)
			(unlocked yes)
			(layer "B.Fab")
			(hide yes)
			(effects
				(font
					(size 1.016 1.016)
					(thickness 0.1524)
				)
				(justify mirror)
			)
		)
		(property "Device Type" "AS0A626-J8R6-7H-COLAY-1"
			(at 41.312338 -18.200878 0)
			(unlocked yes)
			(layer "B.Fab")
			(hide yes)
			(effects
				(font
					(size 1.016 1.016)
					(thickness 0.1524)
				)
				(justify mirror)
			)
		)
		(duplicate_pad_numbers_are_jumpers no)
		(pad "182" smd custom
			(at 25.049988 4.100068 180)
			(size 0.1143 0.1143)
			(layers "B.Cu" "B.Mask" "B.Paste")
			(net "M_B_DQ61")
			(options
				(clearance outline)
				(anchor circle)
			)
			(primitives
				(gr_poly
					(pts
						(xy 0 -0.9017) (xy -0.03175 -0.89916) (xy -0.0635 -0.889) (xy -0.09144 -0.87376) (xy -0.11684 -0.85344)
						(xy -0.13716 -0.82804) (xy -0.1524 -0.8001) (xy -0.16256 -0.76835) (xy -0.1651 -0.7366) (xy -0.1651 0.13462)
						(xy -0.17272 0.14224) (xy -0.19812 0.1778) (xy -0.2032 0.18796) (xy -0.20701 0.19685) (xy -0.21209 0.20701)
						(xy -0.2159 0.21717) (xy -0.21844 0.22733) (xy -0.22225 0.23876) (xy -0.22352 0.24892) (xy -0.22606 0.25908)
						(xy -0.22733 0.27051) (xy -0.22733 0.28067) (xy -0.2286 0.2921) (xy -0.22733 0.30353) (xy -0.22733 0.31369)
						(xy -0.22606 0.32512) (xy -0.22352 0.33528) (xy -0.22225 0.34544) (xy -0.21844 0.35687) (xy -0.2159 0.36703)
						(xy -0.21209 0.37719) (xy -0.20701 0.38735) (xy -0.2032 0.39624) (xy -0.19812 0.4064) (xy -0.17272 0.44196)
						(xy -0.1651 0.44958) (xy -0.1651 0.7366) (xy -0.16256 0.76835) (xy -0.1524 0.8001) (xy -0.13716 0.82804)
						(xy -0.11684 0.85344) (xy -0.09144 0.87376) (xy -0.0635 0.889) (xy -0.03175 0.89916) (xy 0 0.9017)
						(xy 0.03175 0.89916) (xy 0.0635 0.889) (xy 0.09144 0.87376) (xy 0.11684 0.85344) (xy 0.13716 0.82804)
						(xy 0.1524 0.8001) (xy 0.16256 0.76835) (xy 0.1651 0.7366) (xy 0.1651 0.44958) (xy 0.17272 0.44196)
						(xy 0.19812 0.4064) (xy 0.2032 0.39624) (xy 0.20701 0.38735) (xy 0.21209 0.37719) (xy 0.2159 0.36703)
						(xy 0.21844 0.35687) (xy 0.22225 0.34544) (xy 0.22352 0.33528) (xy 0.22606 0.32512) (xy 0.22733 0.31369)
						(xy 0.22733 0.30353) (xy 0.2286 0.2921) (xy 0.22733 0.28067) (xy 0.22733 0.27051) (xy 0.22606 0.25908)
						(xy 0.22352 0.24892) (xy 0.22225 0.23876) (xy 0.21844 0.22733) (xy 0.2159 0.21717) (xy 0.21209 0.20701)
						(xy 0.20701 0.19685) (xy 0.2032 0.18796) (xy 0.19812 0.1778) (xy 0.17272 0.14224) (xy 0.1651 0.13462)
						(xy 0.1651 -0.7366) (xy 0.16256 -0.76835) (xy 0.1524 -0.8001) (xy 0.13716 -0.82804) (xy 0.11684 -0.85344)
						(xy 0.09144 -0.87376) (xy 0.0635 -0.889) (xy 0.03175 -0.89916)
					)
					(width 0)
					(fill yes)
				)
			)
		)
		(pad "183" smd custom
			(at 25.349962 -4.100068 180)
			(size 0.1143 0.1143)
			(layers "B.Cu" "B.Mask" "B.Paste")
			(net "M_B_DQ56")
			(options
				(clearance outline)
				(anchor circle)
			)
			(primitives
				(gr_poly
					(pts
						(xy 0 -0.9017) (xy -0.03175 -0.89916) (xy -0.0635 -0.889) (xy -0.09144 -0.87376) (xy -0.11684 -0.85344)
						(xy -0.13716 -0.82804) (xy -0.1524 -0.8001) (xy -0.16256 -0.76835) (xy -0.1651 -0.7366) (xy -0.1651 -0.19685)
						(xy -0.17272 -0.18923) (xy -0.17907 -0.18034) (xy -0.18669 -0.17145) (xy -0.19177 -0.16256) (xy -0.19812 -0.15367)
						(xy -0.20828 -0.13335) (xy -0.21971 -0.10287) (xy -0.22225 -0.09271) (xy -0.22479 -0.08128) (xy -0.22606 -0.07112)
						(xy -0.2286 -0.05969) (xy -0.2286 -0.01651) (xy -0.22606 -0.00508) (xy -0.22479 0.00508) (xy -0.22225 0.01651)
						(xy -0.21971 0.02667) (xy -0.20828 0.05715) (xy -0.19812 0.07747) (xy -0.19177 0.08636) (xy -0.18669 0.09525)
						(xy -0.17907 0.10414) (xy -0.17272 0.11303) (xy -0.1651 0.12065) (xy -0.1651 0.7366) (xy -0.16256 0.76835)
						(xy -0.1524 0.8001) (xy -0.13716 0.82804) (xy -0.11684 0.85344) (xy -0.09144 0.87376) (xy -0.0635 0.889)
						(xy -0.03175 0.89916) (xy 0 0.9017) (xy 0.03175 0.89916) (xy 0.0635 0.889) (xy 0.09144 0.87376)
						(xy 0.11684 0.85344) (xy 0.13716 0.82804) (xy 0.1524 0.8001) (xy 0.16256 0.76835) (xy 0.1651 0.7366)
						(xy 0.1651 0.11938) (xy 0.17272 0.11176) (xy 0.19812 0.0762) (xy 0.2032 0.06604) (xy 0.20701 0.05715)
						(xy 0.21209 0.04699) (xy 0.2159 0.03683) (xy 0.21844 0.02667) (xy 0.22225 0.01524) (xy 0.22352 0.00508)
						(xy 0.22606 -0.00508) (xy 0.22733 -0.01651) (xy 0.22733 -0.02667) (xy 0.2286 -0.0381) (xy 0.22733 -0.04953)
						(xy 0.22733 -0.05969) (xy 0.22606 -0.07112) (xy 0.22352 -0.08128) (xy 0.22225 -0.09144) (xy 0.21844 -0.10287)
						(xy 0.2159 -0.11303) (xy 0.21209 -0.12319) (xy 0.20701 -0.13335) (xy 0.2032 -0.14224) (xy 0.19812 -0.1524)
						(xy 0.17272 -0.18796) (xy 0.1651 -0.19558) (xy 0.1651 -0.7366) (xy 0.16256 -0.76835) (xy 0.1524 -0.8001)
						(xy 0.13716 -0.82804) (xy 0.11684 -0.85344) (xy 0.09144 -0.87376) (xy 0.0635 -0.889) (xy 0.03175 -0.89916)
					)
					(width 0)
					(fill yes)
				)
			)
		)
		(pad "184" smd custom
			(at 25.649936 4.100068 180)
			(size 0.1143 0.1143)
			(layers "B.Cu" "B.Mask" "B.Paste")
			(net "GND")
			(options
				(clearance outline)
				(anchor circle)
			)
			(primitives
				(gr_poly
					(pts
						(xy 0 -0.9017) (xy -0.03175 -0.89916) (xy -0.0635 -0.889) (xy -0.09144 -0.87376) (xy -0.11684 -0.85344)
						(xy -0.13716 -0.82804) (xy -0.1524 -0.8001) (xy -0.16256 -0.76835) (xy -0.1651 -0.7366) (xy -0.1651 -0.11938)
						(xy -0.17272 -0.11176) (xy -0.19812 -0.0762) (xy -0.2032 -0.06604) (xy -0.20701 -0.05715) (xy -0.21209 -0.04699)
						(xy -0.2159 -0.03683) (xy -0.21844 -0.02667) (xy -0.22225 -0.01524) (xy -0.22352 -0.00508) (xy -0.22606 0.00508)
						(xy -0.22733 0.01651) (xy -0.22733 0.02667) (xy -0.2286 0.0381) (xy -0.22733 0.04953) (xy -0.22733 0.05969)
						(xy -0.22606 0.07112) (xy -0.22352 0.08128) (xy -0.22225 0.09144) (xy -0.21844 0.10287) (xy -0.2159 0.11303)
						(xy -0.21209 0.12319) (xy -0.20701 0.13335) (xy -0.2032 0.14224) (xy -0.19812 0.1524) (xy -0.17272 0.18796)
						(xy -0.1651 0.19558) (xy -0.1651 0.7366) (xy -0.16256 0.76835) (xy -0.1524 0.8001) (xy -0.13716 0.82804)
						(xy -0.11684 0.85344) (xy -0.09144 0.87376) (xy -0.0635 0.889) (xy -0.03175 0.89916) (xy 0 0.9017)
						(xy 0.03175 0.89916) (xy 0.0635 0.889) (xy 0.09144 0.87376) (xy 0.11684 0.85344) (xy 0.13716 0.82804)
						(xy 0.1524 0.8001) (xy 0.16256 0.76835) (xy 0.1651 0.7366) (xy 0.1651 0.19685) (xy 0.17272 0.18923)
						(xy 0.17907 0.18034) (xy 0.18669 0.17145) (xy 0.19177 0.16256) (xy 0.19812 0.15367) (xy 0.20828 0.13335)
						(xy 0.21971 0.10287) (xy 0.22225 0.09271) (xy 0.22479 0.08128) (xy 0.22606 0.07112) (xy 0.2286 0.05969)
						(xy 0.2286 0.01651) (xy 0.22606 0.00508) (xy 0.22479 -0.00508) (xy 0.22225 -0.01651) (xy 0.21971 -0.02667)
						(xy 0.20828 -0.05715) (xy 0.19812 -0.07747) (xy 0.19177 -0.08636) (xy 0.18669 -0.09525) (xy 0.17907 -0.10414)
						(xy 0.17272 -0.11303) (xy 0.1651 -0.12065) (xy 0.1651 -0.7366) (xy 0.16256 -0.76835) (xy 0.1524 -0.8001)
						(xy 0.13716 -0.82804) (xy 0.11684 -0.85344) (xy 0.09144 -0.87376) (xy 0.0635 -0.889) (xy 0.03175 -0.89916)
					)
					(width 0)
					(fill yes)
				)
			)
		)
		(pad "185" smd custom
			(at 25.94991 -4.100068 180)
			(size 0.1143 0.1143)
			(layers "B.Cu" "B.Mask" "B.Paste")
			(net "M_B_DQ57")
			(options
				(clearance outline)
				(anchor circle)
			)
			(primitives
				(gr_poly
					(pts
						(xy 0 -0.9017) (xy -0.03175 -0.89916) (xy -0.0635 -0.889) (xy -0.09144 -0.87376) (xy -0.11684 -0.85344)
						(xy -0.13716 -0.82804) (xy -0.1524 -0.8001) (xy -0.16256 -0.76835) (xy -0.1651 -0.7366) (xy -0.1651 -0.44958)
						(xy -0.17272 -0.44196) (xy -0.19812 -0.4064) (xy -0.2032 -0.39624) (xy -0.20701 -0.38735) (xy -0.21209 -0.37719)
						(xy -0.2159 -0.36703) (xy -0.21844 -0.35687) (xy -0.22225 -0.34544) (xy -0.22352 -0.33528) (xy -0.22606 -0.32512)
						(xy -0.22733 -0.31369) (xy -0.22733 -0.30353) (xy -0.2286 -0.2921) (xy -0.22733 -0.28067) (xy -0.22733 -0.27051)
						(xy -0.22606 -0.25908) (xy -0.22352 -0.24892) (xy -0.22225 -0.23876) (xy -0.21844 -0.22733) (xy -0.2159 -0.21717)
						(xy -0.21209 -0.20701) (xy -0.20701 -0.19685) (xy -0.2032 -0.18796) (xy -0.19812 -0.1778) (xy -0.17272 -0.14224)
						(xy -0.1651 -0.13462) (xy -0.1651 0.7366) (xy -0.16256 0.76835) (xy -0.1524 0.8001) (xy -0.13716 0.82804)
						(xy -0.11684 0.85344) (xy -0.09144 0.87376) (xy -0.0635 0.889) (xy -0.03175 0.89916) (xy 0 0.9017)
						(xy 0.03175 0.89916) (xy 0.0635 0.889) (xy 0.09144 0.87376) (xy 0.11684 0.85344) (xy 0.13716 0.82804)
						(xy 0.1524 0.8001) (xy 0.16256 0.76835) (xy 0.1651 0.7366) (xy 0.1651 -0.13462) (xy 0.17272 -0.14224)
						(xy 0.19812 -0.1778) (xy 0.2032 -0.18796) (xy 0.20701 -0.19685) (xy 0.21209 -0.20701) (xy 0.2159 -0.21717)
						(xy 0.21844 -0.22733) (xy 0.22225 -0.23876) (xy 0.22352 -0.24892) (xy 0.22606 -0.25908) (xy 0.22733 -0.27051)
						(xy 0.22733 -0.28067) (xy 0.2286 -0.2921) (xy 0.22733 -0.30353) (xy 0.22733 -0.31369) (xy 0.22606 -0.32512)
						(xy 0.22352 -0.33528) (xy 0.22225 -0.34544) (xy 0.21844 -0.35687) (xy 0.2159 -0.36703) (xy 0.21209 -0.37719)
						(xy 0.20701 -0.38735) (xy 0.2032 -0.39624) (xy 0.19812 -0.4064) (xy 0.17272 -0.44196) (xy 0.1651 -0.44958)
						(xy 0.1651 -0.7366) (xy 0.16256 -0.76835) (xy 0.1524 -0.8001) (xy 0.13716 -0.82804) (xy 0.11684 -0.85344)
						(xy 0.09144 -0.87376) (xy 0.0635 -0.889) (xy 0.03175 -0.89916)
					)
					(width 0)
					(fill yes)
				)
			)
		)
		(pad "186" smd custom
			(at 26.249884 4.100068 180)
			(size 0.1143 0.1143)
			(layers "B.Cu" "B.Mask" "B.Paste")
			(net "M_B_DQS_DN7")
			(options
				(clearance outline)
				(anchor circle)
			)
			(primitives
				(gr_poly
					(pts
						(xy 0 -0.9017) (xy -0.03175 -0.89916) (xy -0.0635 -0.889) (xy -0.09144 -0.87376) (xy -0.11684 -0.85344)
						(xy -0.13716 -0.82804) (xy -0.1524 -0.8001) (xy -0.16256 -0.76835) (xy -0.1651 -0.7366) (xy -0.1651 0.13462)
						(xy -0.17272 0.14224) (xy -0.19812 0.1778) (xy -0.2032 0.18796) (xy -0.20701 0.19685) (xy -0.21209 0.20701)
						(xy -0.2159 0.21717) (xy -0.21844 0.22733) (xy -0.22225 0.23876) (xy -0.22352 0.24892) (xy -0.22606 0.25908)
						(xy -0.22733 0.27051) (xy -0.22733 0.28067) (xy -0.2286 0.2921) (xy -0.22733 0.30353) (xy -0.22733 0.31369)
						(xy -0.22606 0.32512) (xy -0.22352 0.33528) (xy -0.22225 0.34544) (xy -0.21844 0.35687) (xy -0.2159 0.36703)
						(xy -0.21209 0.37719) (xy -0.20701 0.38735) (xy -0.2032 0.39624) (xy -0.19812 0.4064) (xy -0.17272 0.44196)
						(xy -0.1651 0.44958) (xy -0.1651 0.7366) (xy -0.16256 0.76835) (xy -0.1524 0.8001) (xy -0.13716 0.82804)
						(xy -0.11684 0.85344) (xy -0.09144 0.87376) (xy -0.0635 0.889) (xy -0.03175 0.89916) (xy 0 0.9017)
						(xy 0.03175 0.89916) (xy 0.0635 0.889) (xy 0.09144 0.87376) (xy 0.11684 0.85344) (xy 0.13716 0.82804)
						(xy 0.1524 0.8001) (xy 0.16256 0.76835) (xy 0.1651 0.7366) (xy 0.1651 0.44958) (xy 0.17272 0.44196)
						(xy 0.19812 0.4064) (xy 0.2032 0.39624) (xy 0.20701 0.38735) (xy 0.21209 0.37719) (xy 0.2159 0.36703)
						(xy 0.21844 0.35687) (xy 0.22225 0.34544) (xy 0.22352 0.33528) (xy 0.22606 0.32512) (xy 0.22733 0.31369)
						(xy 0.22733 0.30353) (xy 0.2286 0.2921) (xy 0.22733 0.28067) (xy 0.22733 0.27051) (xy 0.22606 0.25908)
						(xy 0.22352 0.24892) (xy 0.22225 0.23876) (xy 0.21844 0.22733) (xy 0.2159 0.21717) (xy 0.21209 0.20701)
						(xy 0.20701 0.19685) (xy 0.2032 0.18796) (xy 0.19812 0.1778) (xy 0.17272 0.14224) (xy 0.1651 0.13462)
						(xy 0.1651 -0.7366) (xy 0.16256 -0.76835) (xy 0.1524 -0.8001) (xy 0.13716 -0.82804) (xy 0.11684 -0.85344)
						(xy 0.09144 -0.87376) (xy 0.0635 -0.889) (xy 0.03175 -0.89916)
					)
					(width 0)
					(fill yes)
				)
			)
		)
		(pad "187" smd custom
			(at 26.550112 -4.100068 180)
			(size 0.1143 0.1143)
			(layers "B.Cu" "B.Mask" "B.Paste")
			(net "GND")
			(options
				(clearance outline)
				(anchor circle)
			)
			(primitives
				(gr_poly
					(pts
						(xy 0 -0.9017) (xy -0.03175 -0.89916) (xy -0.0635 -0.889) (xy -0.09144 -0.87376) (xy -0.11684 -0.85344)
						(xy -0.13716 -0.82804) (xy -0.1524 -0.8001) (xy -0.16256 -0.76835) (xy -0.1651 -0.7366) (xy -0.1651 -0.19685)
						(xy -0.17272 -0.18923) (xy -0.17907 -0.18034) (xy -0.18669 -0.17145) (xy -0.19177 -0.16256) (xy -0.19812 -0.15367)
						(xy -0.20828 -0.13335) (xy -0.21971 -0.10287) (xy -0.22225 -0.09271) (xy -0.22479 -0.08128) (xy -0.22606 -0.07112)
						(xy -0.2286 -0.05969) (xy -0.2286 -0.01651) (xy -0.22606 -0.00508) (xy -0.22479 0.00508) (xy -0.22225 0.01651)
						(xy -0.21971 0.02667) (xy -0.20828 0.05715) (xy -0.19812 0.07747) (xy -0.19177 0.08636) (xy -0.18669 0.09525)
						(xy -0.17907 0.10414) (xy -0.17272 0.11303) (xy -0.1651 0.12065) (xy -0.1651 0.7366) (xy -0.16256 0.76835)
						(xy -0.1524 0.8001) (xy -0.13716 0.82804) (xy -0.11684 0.85344) (xy -0.09144 0.87376) (xy -0.0635 0.889)
						(xy -0.03175 0.89916) (xy 0 0.9017) (xy 0.03175 0.89916) (xy 0.0635 0.889) (xy 0.09144 0.87376)
						(xy 0.11684 0.85344) (xy 0.13716 0.82804) (xy 0.1524 0.8001) (xy 0.16256 0.76835) (xy 0.1651 0.7366)
						(xy 0.1651 0.11938) (xy 0.17272 0.11176) (xy 0.19812 0.0762) (xy 0.2032 0.06604) (xy 0.20701 0.05715)
						(xy 0.21209 0.04699) (xy 0.2159 0.03683) (xy 0.21844 0.02667) (xy 0.22225 0.01524) (xy 0.22352 0.00508)
						(xy 0.22606 -0.00508) (xy 0.22733 -0.01651) (xy 0.22733 -0.02667) (xy 0.2286 -0.0381) (xy 0.22733 -0.04953)
						(xy 0.22733 -0.05969) (xy 0.22606 -0.07112) (xy 0.22352 -0.08128) (xy 0.22225 -0.09144) (xy 0.21844 -0.10287)
						(xy 0.2159 -0.11303) (xy 0.21209 -0.12319) (xy 0.20701 -0.13335) (xy 0.2032 -0.14224) (xy 0.19812 -0.1524)
						(xy 0.17272 -0.18796) (xy 0.1651 -0.19558) (xy 0.1651 -0.7366) (xy 0.16256 -0.76835) (xy 0.1524 -0.8001)
						(xy 0.13716 -0.82804) (xy 0.11684 -0.85344) (xy 0.09144 -0.87376) (xy 0.0635 -0.889) (xy 0.03175 -0.89916)
					)
					(width 0)
					(fill yes)
				)
			)
		)
		(pad "188" smd custom
			(at 26.850086 4.100068 180)
			(size 0.1143 0.1143)
			(layers "B.Cu" "B.Mask" "B.Paste")
			(net "M_B_DQS_DP7")
			(options
				(clearance outline)
				(anchor circle)
			)
			(primitives
				(gr_poly
					(pts
						(xy 0 -0.9017) (xy -0.03175 -0.89916) (xy -0.0635 -0.889) (xy -0.09144 -0.87376) (xy -0.11684 -0.85344)
						(xy -0.13716 -0.82804) (xy -0.1524 -0.8001) (xy -0.16256 -0.76835) (xy -0.1651 -0.7366) (xy -0.1651 -0.11938)
						(xy -0.17272 -0.11176) (xy -0.19812 -0.0762) (xy -0.2032 -0.06604) (xy -0.20701 -0.05715) (xy -0.21209 -0.04699)
						(xy -0.2159 -0.03683) (xy -0.21844 -0.02667) (xy -0.22225 -0.01524) (xy -0.22352 -0.00508) (xy -0.22606 0.00508)
						(xy -0.22733 0.01651) (xy -0.22733 0.02667) (xy -0.2286 0.0381) (xy -0.22733 0.04953) (xy -0.22733 0.05969)
						(xy -0.22606 0.07112) (xy -0.22352 0.08128) (xy -0.22225 0.09144) (xy -0.21844 0.10287) (xy -0.2159 0.11303)
						(xy -0.21209 0.12319) (xy -0.20701 0.13335) (xy -0.2032 0.14224) (xy -0.19812 0.1524) (xy -0.17272 0.18796)
						(xy -0.1651 0.19558) (xy -0.1651 0.7366) (xy -0.16256 0.76835) (xy -0.1524 0.8001) (xy -0.13716 0.82804)
						(xy -0.11684 0.85344) (xy -0.09144 0.87376) (xy -0.0635 0.889) (xy -0.03175 0.89916) (xy 0 0.9017)
						(xy 0.03175 0.89916) (xy 0.0635 0.889) (xy 0.09144 0.87376) (xy 0.11684 0.85344) (xy 0.13716 0.82804)
						(xy 0.1524 0.8001) (xy 0.16256 0.76835) (xy 0.1651 0.7366) (xy 0.1651 0.19685) (xy 0.17272 0.18923)
						(xy 0.17907 0.18034) (xy 0.18669 0.17145) (xy 0.19177 0.16256) (xy 0.19812 0.15367) (xy 0.20828 0.13335)
						(xy 0.21971 0.10287) (xy 0.22225 0.09271) (xy 0.22479 0.08128) (xy 0.22606 0.07112) (xy 0.2286 0.05969)
						(xy 0.2286 0.01651) (xy 0.22606 0.00508) (xy 0.22479 -0.00508) (xy 0.22225 -0.01651) (xy 0.21971 -0.02667)
						(xy 0.20828 -0.05715) (xy 0.19812 -0.07747) (xy 0.19177 -0.08636) (xy 0.18669 -0.09525) (xy 0.17907 -0.10414)
						(xy 0.17272 -0.11303) (xy 0.1651 -0.12065) (xy 0.1651 -0.7366) (xy 0.16256 -0.76835) (xy 0.1524 -0.8001)
						(xy 0.13716 -0.82804) (xy 0.11684 -0.85344) (xy 0.09144 -0.87376) (xy 0.0635 -0.889) (xy 0.03175 -0.89916)
					)
					(width 0)
					(fill yes)
				)
			)
		)
	)
)
